(kicad_pcb
	(version 20260206)
	(generator "pcbnew")
	(generator_version "10.0")
	(general
		(thickness 1.6)
		(legacy_teardrops no)
	)
	(paper "A4")
	(title_block
		(title "baseboard — 13948-1b.1110WZS1818.brd")
		(comment 1 "Honey Badger (Wiwynn) / footprints 1661-1668 of 2523")
	)
	(layers
		(0 "F.Cu" signal "TOP")
		(4 "In1.Cu" signal "L2GND")
		(6 "In2.Cu" signal "L3")
		(8 "In3.Cu" signal "L4VCC")
		(10 "In4.Cu" signal "L5VCC")
		(12 "In5.Cu" signal "L6")
		(14 "In6.Cu" signal "L7GND")
		(2 "B.Cu" signal "BOTTOM")
		(9 "F.Adhes" user "F.Adhesive")
		(11 "B.Adhes" user "B.Adhesive")
		(13 "F.Paste" user "Package Geometry/Pastemask Top")
		(15 "B.Paste" user "Package Geometry/Pastemask Bottom")
		(5 "F.SilkS" user "Ref Des/Silkscreen Top")
		(7 "B.SilkS" user "Ref Des/Silkscreen Bottom")
		(1 "F.Mask" user "Board Geometry/Soldermask Top")
		(3 "B.Mask" user "Board Geometry/Soldermask Bottom")
		(17 "Dwgs.User" user "User.Drawings")
		(19 "Cmts.User" user "User.Comments")
		(21 "Eco1.User" user "User.Eco1")
		(23 "Eco2.User" user "User.Eco2")
		(25 "Edge.Cuts" user "Board Geometry/Outline")
		(27 "Margin" user)
		(31 "F.CrtYd" user "Package Geometry/Place Bound Top")
		(29 "B.CrtYd" user "Package Geometry/Place Bound Bottom")
		(35 "F.Fab" user "Ref Des/Assembly Top")
		(33 "B.Fab" user "Ref Des/Assembly Bottom")
	)
	(footprint ""
		(layer "F.Cu")
		(at 318.008 -166.878 -90)
		(property "Reference" "R251"
			(at 0 0 270)
			(layer "F.SilkS")
			(hide yes)
			(effects
				(font
					(size 1.27 1.27)
				)
			)
		)
		(property "Value" "0R2J-2-GP"
			(at 0.064008 -3.993896 270)
			(unlocked yes)
			(layer "F.Fab")
			(hide yes)
			(effects
				(font
					(size 1.016 1.016)
					(thickness 0.1524)
				)
			)
		)
		(property "Device Type" "R402H16"
			(at 0.064008 -5.517896 270)
			(unlocked yes)
			(layer "F.Fab")
			(hide yes)
			(effects
				(font
					(size 1.016 1.016)
					(thickness 0.1524)
				)
			)
		)
		(duplicate_pad_numbers_are_jumpers no)
		(fp_line
			(start -0.508 -0.9398)
			(end -0.508 0.9398)
			(stroke
				(width 0.1524)
				(type default)
			)
			(layer "F.SilkS")
		)
		(fp_line
			(start 0.508 -0.9398)
			(end -0.508 -0.9398)
			(stroke
				(width 0.1524)
				(type default)
			)
			(layer "F.SilkS")
		)
		(fp_rect
			(start -0.508 0.9398)
			(end 0.508 -0.9398)
			(stroke
				(width 0)
				(type default)
			)
			(fill no)
			(layer "F.CrtYd")
		)
		(fp_rect
			(start -0.508 0.9398)
			(end 0.508 -0.9398)
			(stroke
				(width 0)
				(type default)
			)
			(fill no)
			(layer "F.Fab")
		)
		(pad "1" smd custom
			(at 0 -0.4445 270)
			(size 0.1397 0.1397)
			(layers "F.Cu" "F.Mask" "F.Paste")
			(net "BMC_I2C_C_SDA")
			(options
				(clearance outline)
				(anchor circle)
			)
			(primitives
				(gr_poly
					(pts
						(arc
							(start -0.1778 -0.2794)
							(mid -0.249642 -0.249642)
							(end -0.2794 -0.1778)
						)
						(arc
							(start -0.2794 0.1778)
							(mid -0.249642 0.249642)
							(end -0.1778 0.2794)
						)
						(arc
							(start 0.1778 0.2794)
							(mid 0.249642 0.249642)
							(end 0.2794 0.1778)
						)
						(arc
							(start 0.2794 -0.1778)
							(mid 0.249642 -0.249642)
							(end 0.1778 -0.2794)
						)
					)
					(width 0)
					(fill yes)
				)
			)
		)
		(pad "2" smd custom
			(at 0 0.4445 270)
			(size 0.1397 0.1397)
			(layers "F.Cu" "F.Mask" "F.Paste")
			(net "BMC0_SMB6_DAT")
			(options
				(clearance outline)
				(anchor circle)
			)
			(primitives
				(gr_poly
					(pts
						(arc
							(start -0.1778 -0.2794)
							(mid -0.249642 -0.249642)
							(end -0.2794 -0.1778)
						)
						(arc
							(start -0.2794 0.1778)
							(mid -0.249642 0.249642)
							(end -0.1778 0.2794)
						)
						(arc
							(start 0.1778 0.2794)
							(mid 0.249642 0.249642)
							(end 0.2794 0.1778)
						)
						(arc
							(start 0.2794 -0.1778)
							(mid 0.249642 -0.249642)
							(end 0.1778 -0.2794)
						)
					)
					(width 0)
					(fill yes)
				)
			)
		)
	)
	(footprint ""
		(layer "F.Cu")
		(at 99.568 -242.189 180)
		(property "Reference" "SR265"
			(at 0 0 180)
			(layer "F.SilkS")
			(hide yes)
			(effects
				(font
					(size 1.27 1.27)
				)
			)
		)
		(property "Value" "0R2J-2-GP"
			(at 0.064008 -3.993896 180)
			(unlocked yes)
			(layer "F.Fab")
			(hide yes)
			(effects
				(font
					(size 1.016 1.016)
					(thickness 0.1524)
				)
			)
		)
		(property "Device Type" "R402H16"
			(at 0.064008 -5.517896 180)
			(unlocked yes)
			(layer "F.Fab")
			(hide yes)
			(effects
				(font
					(size 1.016 1.016)
					(thickness 0.1524)
				)
			)
		)
		(duplicate_pad_numbers_are_jumpers no)
		(fp_line
			(start 0.508 -0.9398)
			(end -0.508 -0.9398)
			(stroke
				(width 0.1524)
				(type default)
			)
			(layer "F.SilkS")
		)
		(fp_line
			(start -0.508 -0.9398)
			(end -0.508 0.9398)
			(stroke
				(width 0.1524)
				(type default)
			)
			(layer "F.SilkS")
		)
		(fp_rect
			(start -0.508 0.9398)
			(end 0.508 -0.9398)
			(stroke
				(width 0)
				(type default)
			)
			(fill no)
			(layer "F.CrtYd")
		)
		(fp_rect
			(start -0.508 0.9398)
			(end 0.508 -0.9398)
			(stroke
				(width 0)
				(type default)
			)
			(fill no)
			(layer "F.Fab")
		)
		(pad "1" smd custom
			(at 0 -0.4445 180)
			(size 0.1397 0.1397)
			(layers "F.Cu" "F.Mask" "F.Paste")
			(net "PCIE_MATED#_LED_CD")
			(options
				(clearance outline)
				(anchor circle)
			)
			(primitives
				(gr_poly
					(pts
						(arc
							(start -0.1778 -0.2794)
							(mid -0.249642 -0.249642)
							(end -0.2794 -0.1778)
						)
						(arc
							(start -0.2794 0.1778)
							(mid -0.249642 0.249642)
							(end -0.1778 0.2794)
						)
						(arc
							(start 0.1778 0.2794)
							(mid 0.249642 0.249642)
							(end 0.2794 0.1778)
						)
						(arc
							(start 0.2794 -0.1778)
							(mid 0.249642 -0.249642)
							(end 0.1778 -0.2794)
						)
					)
					(width 0)
					(fill yes)
				)
			)
		)
		(pad "2" smd custom
			(at 0 0.4445 180)
			(size 0.1397 0.1397)
			(layers "F.Cu" "F.Mask" "F.Paste")
			(net "PCIE_MATED#")
			(options
				(clearance outline)
				(anchor circle)
			)
			(primitives
				(gr_poly
					(pts
						(arc
							(start -0.1778 -0.2794)
							(mid -0.249642 -0.249642)
							(end -0.2794 -0.1778)
						)
						(arc
							(start -0.2794 0.1778)
							(mid -0.249642 0.249642)
							(end -0.1778 0.2794)
						)
						(arc
							(start 0.1778 0.2794)
							(mid 0.249642 0.249642)
							(end 0.2794 0.1778)
						)
						(arc
							(start 0.2794 -0.1778)
							(mid 0.249642 -0.249642)
							(end 0.1778 -0.2794)
						)
					)
					(width 0)
					(fill yes)
				)
			)
		)
	)
	(footprint ""
		(layer "F.Cu")
		(at 179.505864 -22.551136 180)
		(property "Reference" "R383"
			(at 0 0 180)
			(layer "F.SilkS")
			(hide yes)
			(effects
				(font
					(size 1.27 1.27)
				)
			)
		)
		(property "Value" "4K75R2F-1-GP"
			(at 0.064008 -3.993896 180)
			(unlocked yes)
			(layer "F.Fab")
			(hide yes)
			(effects
				(font
					(size 1.016 1.016)
					(thickness 0.1524)
				)
			)
		)
		(property "Device Type" "R402H16"
			(at 0.064008 -5.517896 180)
			(unlocked yes)
			(layer "F.Fab")
			(hide yes)
			(effects
				(font
					(size 1.016 1.016)
					(thickness 0.1524)
				)
			)
		)
		(duplicate_pad_numbers_are_jumpers no)
		(fp_line
			(start 0.508 -0.9398)
			(end -0.508 -0.9398)
			(stroke
				(width 0.1524)
				(type default)
			)
			(layer "F.SilkS")
		)
		(fp_line
			(start -0.508 -0.9398)
			(end -0.508 0.9398)
			(stroke
				(width 0.1524)
				(type default)
			)
			(layer "F.SilkS")
		)
		(fp_rect
			(start -0.508 0.9398)
			(end 0.508 -0.9398)
			(stroke
				(width 0)
				(type default)
			)
			(fill no)
			(layer "F.CrtYd")
		)
		(fp_rect
			(start -0.508 0.9398)
			(end 0.508 -0.9398)
			(stroke
				(width 0)
				(type default)
			)
			(fill no)
			(layer "F.Fab")
		)
		(pad "1" smd custom
			(at 0 -0.4445 180)
			(size 0.1397 0.1397)
			(layers "F.Cu" "F.Mask" "F.Paste")
			(net "P3V3_STBY")
			(options
				(clearance outline)
				(anchor circle)
			)
			(primitives
				(gr_poly
					(pts
						(arc
							(start -0.1778 -0.2794)
							(mid -0.249642 -0.249642)
							(end -0.2794 -0.1778)
						)
						(arc
							(start -0.2794 0.1778)
							(mid -0.249642 0.249642)
							(end -0.1778 0.2794)
						)
						(arc
							(start 0.1778 0.2794)
							(mid 0.249642 0.249642)
							(end 0.2794 0.1778)
						)
						(arc
							(start 0.2794 -0.1778)
							(mid 0.249642 -0.249642)
							(end 0.1778 -0.2794)
						)
					)
					(width 0)
					(fill yes)
				)
			)
		)
		(pad "2" smd custom
			(at 0 0.4445 180)
			(size 0.1397 0.1397)
			(layers "F.Cu" "F.Mask" "F.Paste")
			(net "PHY_F100")
			(options
				(clearance outline)
				(anchor circle)
			)
			(primitives
				(gr_poly
					(pts
						(arc
							(start -0.1778 -0.2794)
							(mid -0.249642 -0.249642)
							(end -0.2794 -0.1778)
						)
						(arc
							(start -0.2794 0.1778)
							(mid -0.249642 0.249642)
							(end -0.1778 0.2794)
						)
						(arc
							(start 0.1778 0.2794)
							(mid 0.249642 0.249642)
							(end 0.2794 0.1778)
						)
						(arc
							(start 0.2794 -0.1778)
							(mid 0.249642 -0.249642)
							(end 0.1778 -0.2794)
						)
					)
					(width 0)
					(fill yes)
				)
			)
		)
	)
	(footprint ""
		(layer "F.Cu")
		(at 177.727864 -34.870136)
		(property "Reference" "TP128"
			(at 0 0 0)
			(layer "F.SilkS")
			(hide yes)
			(effects
				(font
					(size 1.27 1.27)
				)
			)
		)
		(property "Value" "TPAD28"
			(at 0.0127 -1.8034 0)
			(unlocked yes)
			(layer "F.Fab")
			(hide yes)
			(effects
				(font
					(size 1.016 1.016)
					(thickness 0.1524)
				)
			)
		)
		(property "Device Type" "TPAD28"
			(at 0.0127 -3.3274 0)
			(unlocked yes)
			(layer "F.Fab")
			(hide yes)
			(effects
				(font
					(size 1.016 1.016)
					(thickness 0.1524)
				)
			)
		)
		(duplicate_pad_numbers_are_jumpers no)
		(fp_poly
			(pts
				(arc
					(start 0.3556 0)
					(mid -0.3556 0)
					(end 0.3556 0)
				)
			)
			(stroke
				(width 0)
				(type default)
			)
			(fill no)
			(layer "F.CrtYd")
		)
		(fp_poly
			(pts
				(arc
					(start 0.6096 0)
					(mid -0.6096 0)
					(end 0.6096 0)
				)
			)
			(stroke
				(width 0)
				(type default)
			)
			(fill no)
			(layer "F.Fab")
		)
		(pad "1" smd circle
			(at 0 0)
			(size 0.7112 0.7112)
			(layers "F.Cu" "F.Mask" "F.Paste")
			(net "NC_PHY_ENGY_DET")
		)
	)
	(footprint ""
		(layer "F.Cu")
		(at 180.721 -146.431 -90)
		(property "Reference" "SR917"
			(at 0 0 270)
			(layer "F.SilkS")
			(hide yes)
			(effects
				(font
					(size 1.27 1.27)
				)
			)
		)
		(property "Value" "4K7R2F-GP"
			(at 0.064008 -3.993896 270)
			(unlocked yes)
			(layer "F.Fab")
			(hide yes)
			(effects
				(font
					(size 1.016 1.016)
					(thickness 0.1524)
				)
			)
		)
		(property "Device Type" "R402H16"
			(at 0.064008 -5.517896 270)
			(unlocked yes)
			(layer "F.Fab")
			(hide yes)
			(effects
				(font
					(size 1.016 1.016)
					(thickness 0.1524)
				)
			)
		)
		(duplicate_pad_numbers_are_jumpers no)
		(fp_line
			(start -0.508 -0.9398)
			(end -0.508 0.9398)
			(stroke
				(width 0.1524)
				(type default)
			)
			(layer "F.SilkS")
		)
		(fp_line
			(start 0.508 -0.9398)
			(end -0.508 -0.9398)
			(stroke
				(width 0.1524)
				(type default)
			)
			(layer "F.SilkS")
		)
		(fp_rect
			(start -0.508 0.9398)
			(end 0.508 -0.9398)
			(stroke
				(width 0)
				(type default)
			)
			(fill no)
			(layer "F.CrtYd")
		)
		(fp_rect
			(start -0.508 0.9398)
			(end 0.508 -0.9398)
			(stroke
				(width 0)
				(type default)
			)
			(fill no)
			(layer "F.Fab")
		)
		(pad "1" smd custom
			(at 0 -0.4445 270)
			(size 0.1397 0.1397)
			(layers "F.Cu" "F.Mask" "F.Paste")
			(net "BMC_I2C_C_SCL")
			(options
				(clearance outline)
				(anchor circle)
			)
			(primitives
				(gr_poly
					(pts
						(arc
							(start -0.1778 -0.2794)
							(mid -0.249642 -0.249642)
							(end -0.2794 -0.1778)
						)
						(arc
							(start -0.2794 0.1778)
							(mid -0.249642 0.249642)
							(end -0.1778 0.2794)
						)
						(arc
							(start 0.1778 0.2794)
							(mid 0.249642 0.249642)
							(end 0.2794 0.1778)
						)
						(arc
							(start 0.2794 -0.1778)
							(mid 0.249642 -0.249642)
							(end 0.1778 -0.2794)
						)
					)
					(width 0)
					(fill yes)
				)
			)
		)
		(pad "2" smd custom
			(at 0 0.4445 270)
			(size 0.1397 0.1397)
			(layers "F.Cu" "F.Mask" "F.Paste")
			(net "P3V3_STBY")
			(options
				(clearance outline)
				(anchor circle)
			)
			(primitives
				(gr_poly
					(pts
						(arc
							(start -0.1778 -0.2794)
							(mid -0.249642 -0.249642)
							(end -0.2794 -0.1778)
						)
						(arc
							(start -0.2794 0.1778)
							(mid -0.249642 0.249642)
							(end -0.1778 0.2794)
						)
						(arc
							(start 0.1778 0.2794)
							(mid 0.249642 0.249642)
							(end 0.2794 0.1778)
						)
						(arc
							(start 0.2794 -0.1778)
							(mid 0.249642 -0.249642)
							(end 0.1778 -0.2794)
						)
					)
					(width 0)
					(fill yes)
				)
			)
		)
	)
	(footprint ""
		(layer "F.Cu")
		(at 110.11916 -29.845 -90)
		(property "Reference" "SR647"
			(at 0 0 270)
			(layer "F.SilkS")
			(hide yes)
			(effects
				(font
					(size 1.27 1.27)
				)
			)
		)
		(property "Value" "4K7R2F-GP"
			(at 0.064008 -3.993896 270)
			(unlocked yes)
			(layer "F.Fab")
			(hide yes)
			(effects
				(font
					(size 1.016 1.016)
					(thickness 0.1524)
				)
			)
		)
		(property "Device Type" "R402H16"
			(at 0.064008 -5.517896 270)
			(unlocked yes)
			(layer "F.Fab")
			(hide yes)
			(effects
				(font
					(size 1.016 1.016)
					(thickness 0.1524)
				)
			)
		)
		(duplicate_pad_numbers_are_jumpers no)
		(fp_line
			(start -0.508 -0.9398)
			(end -0.508 0.9398)
			(stroke
				(width 0.1524)
				(type default)
			)
			(layer "F.SilkS")
		)
		(fp_line
			(start 0.508 -0.9398)
			(end -0.508 -0.9398)
			(stroke
				(width 0.1524)
				(type default)
			)
			(layer "F.SilkS")
		)
		(fp_rect
			(start -0.508 0.9398)
			(end 0.508 -0.9398)
			(stroke
				(width 0)
				(type default)
			)
			(fill no)
			(layer "F.CrtYd")
		)
		(fp_rect
			(start -0.508 0.9398)
			(end 0.508 -0.9398)
			(stroke
				(width 0)
				(type default)
			)
			(fill no)
			(layer "F.Fab")
		)
		(pad "1" smd custom
			(at 0 -0.4445 270)
			(size 0.1397 0.1397)
			(layers "F.Cu" "F.Mask" "F.Paste")
			(net "P1V8_C")
			(options
				(clearance outline)
				(anchor circle)
			)
			(primitives
				(gr_poly
					(pts
						(arc
							(start -0.1778 -0.2794)
							(mid -0.249642 -0.249642)
							(end -0.2794 -0.1778)
						)
						(arc
							(start -0.2794 0.1778)
							(mid -0.249642 0.249642)
							(end -0.1778 0.2794)
						)
						(arc
							(start 0.1778 0.2794)
							(mid 0.249642 0.249642)
							(end 0.2794 0.1778)
						)
						(arc
							(start 0.2794 -0.1778)
							(mid 0.249642 -0.249642)
							(end 0.1778 -0.2794)
						)
					)
					(width 0)
					(fill yes)
				)
			)
		)
		(pad "2" smd custom
			(at 0 0.4445 270)
			(size 0.1397 0.1397)
			(layers "F.Cu" "F.Mask" "F.Paste")
			(net "IOC_UART_0_RX")
			(options
				(clearance outline)
				(anchor circle)
			)
			(primitives
				(gr_poly
					(pts
						(arc
							(start -0.1778 -0.2794)
							(mid -0.249642 -0.249642)
							(end -0.2794 -0.1778)
						)
						(arc
							(start -0.2794 0.1778)
							(mid -0.249642 0.249642)
							(end -0.1778 0.2794)
						)
						(arc
							(start 0.1778 0.2794)
							(mid 0.249642 0.249642)
							(end 0.2794 0.1778)
						)
						(arc
							(start 0.2794 -0.1778)
							(mid 0.249642 -0.249642)
							(end 0.1778 -0.2794)
						)
					)
					(width 0)
					(fill yes)
				)
			)
		)
	)
	(footprint ""
		(layer "F.Cu")
		(at 279.899872 -205.304136)
		(property "Reference" "R491"
			(at 0 0 0)
			(layer "F.SilkS")
			(hide yes)
			(effects
				(font
					(size 1.27 1.27)
				)
			)
		)
		(property "Value" "0R2J-2-GP"
			(at 0.064008 -3.993896 0)
			(unlocked yes)
			(layer "F.Fab")
			(hide yes)
			(effects
				(font
					(size 1.016 1.016)
					(thickness 0.1524)
				)
			)
		)
		(property "Device Type" "R402H16"
			(at 0.064008 -5.517896 0)
			(unlocked yes)
			(layer "F.Fab")
			(hide yes)
			(effects
				(font
					(size 1.016 1.016)
					(thickness 0.1524)
				)
			)
		)
		(duplicate_pad_numbers_are_jumpers no)
		(fp_line
			(start -0.508 -0.9398)
			(end -0.508 0.9398)
			(stroke
				(width 0.1524)
				(type default)
			)
			(layer "F.SilkS")
		)
		(fp_line
			(start 0.508 -0.9398)
			(end -0.508 -0.9398)
			(stroke
				(width 0.1524)
				(type default)
			)
			(layer "F.SilkS")
		)
		(fp_rect
			(start -0.508 0.9398)
			(end 0.508 -0.9398)
			(stroke
				(width 0)
				(type default)
			)
			(fill no)
			(layer "F.CrtYd")
		)
		(fp_rect
			(start -0.508 0.9398)
			(end 0.508 -0.9398)
			(stroke
				(width 0)
				(type default)
			)
			(fill no)
			(layer "F.Fab")
		)
		(pad "1" smd custom
			(at 0 -0.4445)
			(size 0.1397 0.1397)
			(layers "F.Cu" "F.Mask" "F.Paste")
			(net "RST_BMC_DDR3_R_N")
			(options
				(clearance outline)
				(anchor circle)
			)
			(primitives
				(gr_poly
					(pts
						(arc
							(start -0.1778 -0.2794)
							(mid -0.249642 -0.249642)
							(end -0.2794 -0.1778)
						)
						(arc
							(start -0.2794 0.1778)
							(mid -0.249642 0.249642)
							(end -0.1778 0.2794)
						)
						(arc
							(start 0.1778 0.2794)
							(mid 0.249642 0.249642)
							(end 0.2794 0.1778)
						)
						(arc
							(start 0.2794 -0.1778)
							(mid 0.249642 -0.249642)
							(end 0.1778 -0.2794)
						)
					)
					(width 0)
					(fill yes)
				)
			)
		)
		(pad "2" smd custom
			(at 0 0.4445)
			(size 0.1397 0.1397)
			(layers "F.Cu" "F.Mask" "F.Paste")
			(net "BMC_DDR3_RST_N")
			(options
				(clearance outline)
				(anchor circle)
			)
			(primitives
				(gr_poly
					(pts
						(arc
							(start -0.1778 -0.2794)
							(mid -0.249642 -0.249642)
							(end -0.2794 -0.1778)
						)
						(arc
							(start -0.2794 0.1778)
							(mid -0.249642 0.249642)
							(end -0.1778 0.2794)
						)
						(arc
							(start 0.1778 0.2794)
							(mid 0.249642 0.249642)
							(end 0.2794 0.1778)
						)
						(arc
							(start 0.2794 -0.1778)
							(mid 0.249642 -0.249642)
							(end 0.1778 -0.2794)
						)
					)
					(width 0)
					(fill yes)
				)
			)
		)
	)
	(footprint ""
		(layer "F.Cu")
		(at 158.369 -106.934 90)
		(property "Reference" "SC1209"
			(at 0 0 90)
			(layer "F.SilkS")
			(hide yes)
			(effects
				(font
					(size 1.27 1.27)
				)
			)
		)
		(property "Value" "SC10U6D3V5KX-4GP"
			(at -0.0762 -6.1214 90)
			(unlocked yes)
			(layer "F.Fab")
			(hide yes)
			(effects
				(font
					(size 1.016 1.016)
					(thickness 0.1524)
				)
			)
		)
		(property "Device Type" "C805H58"
			(at -0.0762 -8.1534 90)
			(unlocked yes)
			(layer "F.Fab")
			(hide yes)
			(effects
				(font
					(size 1.016 1.016)
					(thickness 0.1524)
				)
			)
		)
		(duplicate_pad_numbers_are_jumpers no)
		(fp_line
			(start 0.635 0)
			(end -0.635 0)
			(stroke
				(width 0.508)
				(type default)
			)
			(layer "F.SilkS")
		)
		(fp_rect
			(start -0.9652 1.778)
			(end 0.9652 -1.778)
			(stroke
				(width 0)
				(type default)
			)
			(fill no)
			(layer "F.CrtYd")
		)
		(fp_poly
			(pts
				(xy -0.9652 -1.778) (xy 0.9652 -1.778) (xy 0.9652 1.778) (xy -0.9652 1.778)
			)
			(stroke
				(width 0)
				(type default)
			)
			(fill no)
			(layer "F.Fab")
		)
		(pad "1" smd rect
			(at 0 -0.9652 90)
			(size 1.397 1.143)
			(layers "F.Cu" "F.Mask" "F.Paste")
			(net "P0V9_E")
		)
		(pad "2" smd rect
			(at 0 0.9652 90)
			(size 1.397 1.143)
			(layers "F.Cu" "F.Mask" "F.Paste")
			(net "GND")
		)
	)
)
